# T6G (Grand Teton) — schematic netlist excerpt (pin names and nets, part order shuffled) for the footprints in the layout excerpt that follows; sources: Cadence DE-HDL packaged netlist, KiCad conversion of 04192023_DAF0TMB3IC0_F0TG_MB_C_brd_V02_OCP.brd

PC6617_1  Q_CAP  22UF 16V 20% X6S  pkg C0805  page 365 : A = SW_P12V_AUX_P0V9_RETIMER_CPU1_FLT ; B = GND
C453  Q_CAP  1UF 4V 20% X6S  pkg 0201  page 356 : A = P0V9_CPU1_RT3_2A ; B = GND
C7023  Q_CAPP  470UF 2.5V 20% SPCAP  pkg SMLF  page 334 : A = P0V9_CPU1_RT1_2A ; B = GND

(kicad_pcb
	(version 20260206)
	(generator "pcbnew")
	(generator_version "10.0")
	(general
		(thickness 1.6)
		(legacy_teardrops no)
	)
	(paper "A4")
	(title_block
		(title "04192023_DAF0TMB3IC0_F0TG_MB_C_brd_V02_OCP.brd")
		(comment 1 "Grand Teton / footprints 6187-6189 of 8354")
	)
	(layers
		(0 "F.Cu" signal "TOP")
		(4 "In1.Cu" signal "GND")
		(6 "In2.Cu" signal "IN1")
		(8 "In3.Cu" signal "GND1")
		(10 "In4.Cu" signal "IN2")
		(12 "In5.Cu" signal "GND2")
		(14 "In6.Cu" signal "IN3")
		(16 "In7.Cu" signal "GND3")
		(18 "In8.Cu" signal "VCC")
		(20 "In9.Cu" signal "VCC1")
		(22 "In10.Cu" signal "GND4")
		(24 "In11.Cu" signal "IN4")
		(26 "In12.Cu" signal "GND5")
		(28 "In13.Cu" signal "IN5")
		(30 "In14.Cu" signal "GND6")
		(32 "In15.Cu" signal "IN6")
		(34 "In16.Cu" signal "GND7")
		(2 "B.Cu" signal "BOTTOM")
		(9 "F.Adhes" user "F.Adhesive")
		(11 "B.Adhes" user "B.Adhesive")
		(13 "F.Paste" user "Package Geometry/Pastemask Top")
		(15 "B.Paste" user "Package Geometry/Pastemask Bottom")
		(5 "F.SilkS" user "Ref Des/Silkscreen Top")
		(7 "B.SilkS" user "Ref Des/Silkscreen Bottom")
		(1 "F.Mask" user "Board Geometry/Soldermask Top")
		(3 "B.Mask" user "Board Geometry/Soldermask Bottom")
		(17 "Dwgs.User" user "User.Drawings")
		(19 "Cmts.User" user "User.Comments")
		(21 "Eco1.User" user "User.Eco1")
		(23 "Eco2.User" user "User.Eco2")
		(25 "Edge.Cuts" user "Board Geometry/Outline")
		(27 "Margin" user)
		(31 "F.CrtYd" user "Package Geometry/Place Bound Top")
		(29 "B.CrtYd" user "Package Geometry/Place Bound Bottom")
		(35 "F.Fab" user "Ref Des/Assembly Top")
		(33 "B.Fab" user "Ref Des/Assembly Bottom")
	)
	(footprint ""
		(layer "B.Cu")
		(at 94.49562 -381.11303)
		(property "Reference" "C7023"
			(at 2.6416 2.989072 0)
			(unlocked yes)
			(layer "B.SilkS")
			(effects
				(font
					(size 0.7874 0.5842)
					(thickness 0.1524)
				)
				(justify left mirror)
			)
		)
		(property "Value" ""
			(at 0 0 0)
			(layer "B.Fab")
			(effects
				(font
					(size 1.27 1.27)
				)
				(justify mirror)
			)
		)
		(duplicate_pad_numbers_are_jumpers no)
		(fp_line
			(start -4.53898 -2.15011)
			(end -4.53898 2.15011)
			(stroke
				(width 0.1524)
				(type default)
			)
			(layer "B.SilkS")
		)
		(fp_line
			(start -4.53898 2.15011)
			(end 4.53898 2.15011)
			(stroke
				(width 0.1524)
				(type default)
			)
			(layer "B.SilkS")
		)
		(fp_line
			(start 4.53898 -2.150618)
			(end 4.539742 2.152142)
			(stroke
				(width 0.1524)
				(type default)
			)
			(layer "B.SilkS")
		)
		(fp_line
			(start 4.53898 -2.15011)
			(end -4.53898 -2.15011)
			(stroke
				(width 0.1524)
				(type default)
			)
			(layer "B.SilkS")
		)
		(fp_line
			(start 4.53898 2.15011)
			(end 4.53898 -2.15011)
			(stroke
				(width 0.1524)
				(type default)
			)
			(layer "B.SilkS")
		)
		(fp_line
			(start 4.69138 -2.150618)
			(end 4.692396 2.161032)
			(stroke
				(width 0.1524)
				(type default)
			)
			(layer "B.SilkS")
		)
		(fp_line
			(start 4.83108 2.150364)
			(end 4.447794 2.149348)
			(stroke
				(width 0.1524)
				(type default)
			)
			(layer "B.SilkS")
		)
		(fp_line
			(start 4.84378 -2.150618)
			(end 4.53898 -2.150618)
			(stroke
				(width 0.1524)
				(type default)
			)
			(layer "B.SilkS")
		)
		(fp_line
			(start 4.84378 -2.150618)
			(end 4.842256 2.163064)
			(stroke
				(width 0.1524)
				(type default)
			)
			(layer "B.SilkS")
		)
		(fp_line
			(start -3.64998 -2.15011)
			(end -3.64998 2.15011)
			(stroke
				(width 0.1)
				(type default)
			)
			(layer "B.Fab")
		)
		(fp_line
			(start -3.64998 2.15011)
			(end 3.64998 2.15011)
			(stroke
				(width 0.1)
				(type default)
			)
			(layer "B.Fab")
		)
		(fp_line
			(start 3.64998 -2.15011)
			(end -3.64998 -2.15011)
			(stroke
				(width 0.1)
				(type default)
			)
			(layer "B.Fab")
		)
		(fp_line
			(start 3.64998 2.15011)
			(end 3.64998 -2.15011)
			(stroke
				(width 0.1)
				(type default)
			)
			(layer "B.Fab")
		)
		(fp_text user "-"
			(at -2.827274 2.572512 0)
			(unlocked yes)
			(layer "B.SilkS")
			(effects
				(font
					(size 1.905 1.4224)
					(thickness 0.1524)
				)
				(justify left mirror)
			)
		)
		(fp_text user "+"
			(at 6.214872 -0.337058 0)
			(unlocked yes)
			(layer "B.SilkS")
			(effects
				(font
					(size 1.905 1.4224)
					(thickness 0.1524)
				)
				(justify left mirror)
			)
		)
		(fp_text user "-"
			(at -4.313174 -0.094488 0)
			(unlocked yes)
			(layer "B.Fab")
			(effects
				(font
					(size 1.905 1.4224)
					(thickness 0.1524)
				)
				(justify left mirror)
			)
		)
		(fp_text user "+"
			(at 6.214872 -0.337058 0)
			(unlocked yes)
			(layer "B.Fab")
			(effects
				(font
					(size 1.905 1.4224)
					(thickness 0.1524)
				)
				(justify left mirror)
			)
		)
		(pad "1" smd rect
			(at 3.199892 0 180)
			(size 2.413 2.8194)
			(layers "B.Cu" "B.Mask" "B.Paste")
			(net "P0V9_CPU1_RT1_2A")
		)
		(pad "2" smd rect
			(at -3.199892 0 180)
			(size 2.413 2.8194)
			(layers "B.Cu" "B.Mask" "B.Paste")
			(net "GND")
		)
	)
	(footprint ""
		(layer "B.Cu")
		(at 128.878584 -386.766562 90)
		(property "Reference" "C453"
			(at 0 0 90)
			(layer "B.SilkS")
			(hide yes)
			(effects
				(font
					(size 1.27 1.27)
				)
				(justify mirror)
			)
		)
		(property "Value" ""
			(at 0 0 90)
			(layer "B.Fab")
			(effects
				(font
					(size 1.27 1.27)
				)
				(justify mirror)
			)
		)
		(duplicate_pad_numbers_are_jumpers no)
		(fp_line
			(start 0.299974 -0.150114)
			(end -0.299974 -0.150114)
			(stroke
				(width 0.1)
				(type default)
			)
			(layer "B.Fab")
		)
		(fp_line
			(start -0.299974 -0.150114)
			(end -0.299974 0.150114)
			(stroke
				(width 0.1)
				(type default)
			)
			(layer "B.Fab")
		)
		(fp_line
			(start 0.299974 0.150114)
			(end 0.299974 -0.150114)
			(stroke
				(width 0.1)
				(type default)
			)
			(layer "B.Fab")
		)
		(fp_line
			(start -0.299974 0.150114)
			(end 0.299974 0.150114)
			(stroke
				(width 0.1)
				(type default)
			)
			(layer "B.Fab")
		)
		(pad "1" smd rect
			(at 0.2667 0 270)
			(size 0.3048 0.381)
			(layers "B.Cu" "B.Mask" "B.Paste")
			(net "P0V9_CPU1_RT3_2A")
		)
		(pad "2" smd rect
			(at -0.2667 0 270)
			(size 0.3048 0.381)
			(layers "B.Cu" "B.Mask" "B.Paste")
			(net "GND")
		)
	)
	(footprint ""
		(layer "B.Cu")
		(at 18.039588 -397.456406)
		(property "Reference" "PC6617_1"
			(at 0 0 0)
			(layer "B.SilkS")
			(hide yes)
			(effects
				(font
					(size 1.27 1.27)
				)
				(justify mirror)
			)
		)
		(property "Value" ""
			(at 0 0 0)
			(layer "B.Fab")
			(effects
				(font
					(size 1.27 1.27)
				)
				(justify mirror)
			)
		)
		(duplicate_pad_numbers_are_jumpers no)
		(fp_line
			(start -1.524 -0.762)
			(end -1.524 0.762)
			(stroke
				(width 0.1524)
				(type default)
			)
			(layer "B.SilkS")
		)
		(fp_line
			(start -1.524 0.762)
			(end 1.524 0.762)
			(stroke
				(width 0.1524)
				(type default)
			)
			(layer "B.SilkS")
		)
		(fp_line
			(start 1.524 -0.762)
			(end -1.524 -0.762)
			(stroke
				(width 0.1524)
				(type default)
			)
			(layer "B.SilkS")
		)
		(fp_line
			(start 1.524 0.762)
			(end 1.524 -0.762)
			(stroke
				(width 0.1524)
				(type default)
			)
			(layer "B.SilkS")
		)
		(fp_line
			(start -1.1049 -0.724916)
			(end 1.1049 -0.724916)
			(stroke
				(width 0.1)
				(type default)
			)
			(layer "B.Fab")
		)
		(fp_line
			(start -1.1049 0.724916)
			(end -1.1049 -0.724916)
			(stroke
				(width 0.1)
				(type default)
			)
			(layer "B.Fab")
		)
		(fp_line
			(start 1.1049 -0.724916)
			(end 1.1049 0.724916)
			(stroke
				(width 0.1)
				(type default)
			)
			(layer "B.Fab")
		)
		(fp_line
			(start 1.1049 0.724916)
			(end -1.1049 0.724916)
			(stroke
				(width 0.1)
				(type default)
			)
			(layer "B.Fab")
		)
		(pad "1" smd rect
			(at 0.889 0)
			(size 1.016 1.27)
			(layers "B.Cu" "B.Mask" "B.Paste")
			(net "SW_P12V_AUX_P0V9_RETIMER_CPU1_FLT")
		)
		(pad "2" smd rect
			(at -0.889 0)
			(size 1.016 1.27)
			(layers "B.Cu" "B.Mask" "B.Paste")
			(net "GND")
		)
	)
)
